# S9S_MB_2U (Grand Teton) — schematic netlist excerpt (pin names and nets, part order shuffled) for the footprints in the layout excerpt that follows; sources: Cadence DE-HDL packaged netlist, KiCad conversion of 03242023_DA0F0TMBIJ0_F0T_Motherboard_J_brd_V01_OCP.brd

PC1245_P1_4  Q_CAP  2.2UF 10V 10% X6S  pkg C0402  page 290 : A = PVCCFA_EHV_FIVRA_CPU1_PVCC2 ; B = GND
PR1330  Q_RES  150K 1% CHIP  pkg 0402LF  page 263 : A = P1V8_PCH_AUX_MODE ; B = GND

(kicad_pcb
	(version 20260206)
	(generator "pcbnew")
	(generator_version "10.0")
	(general
		(thickness 1.6)
		(legacy_teardrops no)
	)
	(paper "A4")
	(title_block
		(title "03242023_DA0F0TMBIJ0_F0T_Motherboard_J_brd_V01_OCP.brd")
		(comment 1 "Grand Teton / footprints 1075-1076 of 6105")
	)
	(layers
		(0 "F.Cu" signal "TOP")
		(4 "In1.Cu" signal "GND")
		(6 "In2.Cu" signal "IN1")
		(8 "In3.Cu" signal "GND1")
		(10 "In4.Cu" signal "IN2")
		(12 "In5.Cu" signal "GND2")
		(14 "In6.Cu" signal "IN3")
		(16 "In7.Cu" signal "GND3")
		(18 "In8.Cu" signal "VCC")
		(20 "In9.Cu" signal "VCC1")
		(22 "In10.Cu" signal "GND4")
		(24 "In11.Cu" signal "IN4")
		(26 "In12.Cu" signal "GND5")
		(28 "In13.Cu" signal "IN5")
		(30 "In14.Cu" signal "GND6")
		(32 "In15.Cu" signal "IN6")
		(34 "In16.Cu" signal "GND7")
		(2 "B.Cu" signal "BOTTOM")
		(9 "F.Adhes" user "F.Adhesive")
		(11 "B.Adhes" user "B.Adhesive")
		(13 "F.Paste" user "Package Geometry/Pastemask Top")
		(15 "B.Paste" user "Package Geometry/Pastemask Bottom")
		(5 "F.SilkS" user "Ref Des/Silkscreen Top")
		(7 "B.SilkS" user "Ref Des/Silkscreen Bottom")
		(1 "F.Mask" user "Board Geometry/Soldermask Top")
		(3 "B.Mask" user "Board Geometry/Soldermask Bottom")
		(17 "Dwgs.User" user "User.Drawings")
		(19 "Cmts.User" user "User.Comments")
		(21 "Eco1.User" user "User.Eco1")
		(23 "Eco2.User" user "User.Eco2")
		(25 "Edge.Cuts" user "Board Geometry/Outline")
		(27 "Margin" user)
		(31 "F.CrtYd" user "Package Geometry/Place Bound Top")
		(29 "B.CrtYd" user "Package Geometry/Place Bound Bottom")
		(35 "F.Fab" user "Ref Des/Assembly Top")
		(33 "B.Fab" user "Ref Des/Assembly Bottom")
	)
	(footprint ""
		(layer "F.Cu")
		(at 382.168908 -78.424024 90)
		(property "Reference" "PR1330"
			(at 0 0 90)
			(layer "F.SilkS")
			(hide yes)
			(effects
				(font
					(size 1.27 1.27)
				)
			)
		)
		(property "Value" ""
			(at 0 0 90)
			(layer "F.Fab")
			(effects
				(font
					(size 1.27 1.27)
				)
			)
		)
		(duplicate_pad_numbers_are_jumpers no)
		(fp_line
			(start 0.7874 -0.4064)
			(end 0.7874 0.4064)
			(stroke
				(width 0.1524)
				(type default)
			)
			(layer "F.SilkS")
		)
		(fp_line
			(start -0.7874 -0.4064)
			(end 0.7874 -0.4064)
			(stroke
				(width 0.1524)
				(type default)
			)
			(layer "F.SilkS")
		)
		(fp_line
			(start 0.7874 0.4064)
			(end -0.7874 0.4064)
			(stroke
				(width 0.1524)
				(type default)
			)
			(layer "F.SilkS")
		)
		(fp_line
			(start -0.7874 0.4064)
			(end -0.7874 -0.4064)
			(stroke
				(width 0.1524)
				(type default)
			)
			(layer "F.SilkS")
		)
		(fp_line
			(start -0.12065 -0.305054)
			(end -0.12065 -0.2794)
			(stroke
				(width 0.1)
				(type default)
			)
			(layer "F.Fab")
		)
		(fp_line
			(start -0.67945 -0.305054)
			(end -0.12065 -0.305054)
			(stroke
				(width 0.1)
				(type default)
			)
			(layer "F.Fab")
		)
		(fp_line
			(start 0.67945 -0.3048)
			(end 0.67945 0.3048)
			(stroke
				(width 0.1)
				(type default)
			)
			(layer "F.Fab")
		)
		(fp_line
			(start 0.12065 -0.3048)
			(end 0.67945 -0.3048)
			(stroke
				(width 0.1)
				(type default)
			)
			(layer "F.Fab")
		)
		(fp_line
			(start 0.12065 -0.2794)
			(end 0.12065 -0.3048)
			(stroke
				(width 0.1)
				(type default)
			)
			(layer "F.Fab")
		)
		(fp_line
			(start -0.12065 -0.2794)
			(end 0.12065 -0.2794)
			(stroke
				(width 0.1)
				(type default)
			)
			(layer "F.Fab")
		)
		(fp_line
			(start 0.120396 0.2794)
			(end -0.12065 0.2794)
			(stroke
				(width 0.1)
				(type default)
			)
			(layer "F.Fab")
		)
		(fp_line
			(start -0.12065 0.2794)
			(end -0.12065 0.3048)
			(stroke
				(width 0.1)
				(type default)
			)
			(layer "F.Fab")
		)
		(fp_line
			(start 0.67945 0.3048)
			(end 0.120396 0.3048)
			(stroke
				(width 0.1)
				(type default)
			)
			(layer "F.Fab")
		)
		(fp_line
			(start 0.120396 0.3048)
			(end 0.120396 0.2794)
			(stroke
				(width 0.1)
				(type default)
			)
			(layer "F.Fab")
		)
		(fp_line
			(start -0.12065 0.3048)
			(end -0.67945 0.3048)
			(stroke
				(width 0.1)
				(type default)
			)
			(layer "F.Fab")
		)
		(fp_line
			(start -0.67945 0.3048)
			(end -0.67945 -0.305054)
			(stroke
				(width 0.1)
				(type default)
			)
			(layer "F.Fab")
		)
		(pad "1" smd circle
			(at -0.40005 0 90)
			(size 0 0)
			(layers "F.Cu" "F.Mask" "F.Paste")
			(net "P1V8_PCH_AUX_MODE")
		)
		(pad "2" smd circle
			(at 0.40005 0 90)
			(size 0 0)
			(layers "F.Cu" "F.Mask" "F.Paste")
			(net "GND")
		)
	)
	(footprint ""
		(layer "F.Cu")
		(at 37.990272 -353.35718 -90)
		(property "Reference" "PC1245_P1_4"
			(at 0 0 270)
			(layer "F.SilkS")
			(hide yes)
			(effects
				(font
					(size 1.27 1.27)
				)
			)
		)
		(property "Value" ""
			(at 0 0 270)
			(layer "F.Fab")
			(effects
				(font
					(size 1.27 1.27)
				)
			)
		)
		(duplicate_pad_numbers_are_jumpers no)
		(fp_line
			(start -0.7874 0.4064)
			(end -0.7874 -0.4064)
			(stroke
				(width 0.1524)
				(type default)
			)
			(layer "F.SilkS")
		)
		(fp_line
			(start 0.7874 0.4064)
			(end -0.7874 0.4064)
			(stroke
				(width 0.1524)
				(type default)
			)
			(layer "F.SilkS")
		)
		(fp_line
			(start -0.7874 -0.4064)
			(end 0.7874 -0.4064)
			(stroke
				(width 0.1524)
				(type default)
			)
			(layer "F.SilkS")
		)
		(fp_line
			(start 0.7874 -0.4064)
			(end 0.7874 0.4064)
			(stroke
				(width 0.1524)
				(type default)
			)
			(layer "F.SilkS")
		)
		(fp_line
			(start -0.67945 0.3048)
			(end -0.67945 -0.305054)
			(stroke
				(width 0.1)
				(type default)
			)
			(layer "F.Fab")
		)
		(fp_line
			(start -0.12065 0.3048)
			(end -0.67945 0.3048)
			(stroke
				(width 0.1)
				(type default)
			)
			(layer "F.Fab")
		)
		(fp_line
			(start 0.120396 0.3048)
			(end 0.120396 0.2794)
			(stroke
				(width 0.1)
				(type default)
			)
			(layer "F.Fab")
		)
		(fp_line
			(start 0.67945 0.3048)
			(end 0.120396 0.3048)
			(stroke
				(width 0.1)
				(type default)
			)
			(layer "F.Fab")
		)
		(fp_line
			(start -0.12065 0.2794)
			(end -0.12065 0.3048)
			(stroke
				(width 0.1)
				(type default)
			)
			(layer "F.Fab")
		)
		(fp_line
			(start 0.120396 0.2794)
			(end -0.12065 0.2794)
			(stroke
				(width 0.1)
				(type default)
			)
			(layer "F.Fab")
		)
		(fp_line
			(start -0.12065 -0.2794)
			(end 0.12065 -0.2794)
			(stroke
				(width 0.1)
				(type default)
			)
			(layer "F.Fab")
		)
		(fp_line
			(start 0.12065 -0.2794)
			(end 0.12065 -0.3048)
			(stroke
				(width 0.1)
				(type default)
			)
			(layer "F.Fab")
		)
		(fp_line
			(start 0.12065 -0.3048)
			(end 0.67945 -0.3048)
			(stroke
				(width 0.1)
				(type default)
			)
			(layer "F.Fab")
		)
		(fp_line
			(start 0.67945 -0.3048)
			(end 0.67945 0.3048)
			(stroke
				(width 0.1)
				(type default)
			)
			(layer "F.Fab")
		)
		(fp_line
			(start -0.67945 -0.305054)
			(end -0.12065 -0.305054)
			(stroke
				(width 0.1)
				(type default)
			)
			(layer "F.Fab")
		)
		(fp_line
			(start -0.12065 -0.305054)
			(end -0.12065 -0.2794)
			(stroke
				(width 0.1)
				(type default)
			)
			(layer "F.Fab")
		)
		(pad "1" smd circle
			(at -0.40005 0 270)
			(size 0 0)
			(layers "F.Cu" "F.Mask" "F.Paste")
			(net "PVCCFA_EHV_FIVRA_CPU1_PVCC2")
		)
		(pad "2" smd circle
			(at 0.40005 0 270)
			(size 0 0)
			(layers "F.Cu" "F.Mask" "F.Paste")
			(net "GND")
		)
	)
)
